(kicad_pcb
	(version 20260206)
	(generator "pcbnew")
	(generator_version "10.0")
	(general
		(thickness 1.6)
		(legacy_teardrops no)
	)
	(paper "A4")
	(title_block
		(title "Bryce Canyon_F.DPB_16315-1-OCP.brd")
		(comment 1 "Bryce Canyon / footprints 466-469 of 2223")
	)
	(layers
		(0 "F.Cu" signal "TOP")
		(4 "In1.Cu" signal "L2GND")
		(6 "In2.Cu" signal "L3")
		(8 "In3.Cu" signal "L4GND")
		(10 "In4.Cu" signal "L5")
		(12 "In5.Cu" signal "L6VCC")
		(14 "In6.Cu" signal "L7VCC")
		(16 "In7.Cu" signal "L8")
		(18 "In8.Cu" signal "L9GND")
		(20 "In9.Cu" signal "L10")
		(22 "In10.Cu" signal "L11GND")
		(2 "B.Cu" signal "BOTTOM")
		(9 "F.Adhes" user "F.Adhesive")
		(11 "B.Adhes" user "B.Adhesive")
		(13 "F.Paste" user "Package Geometry/Pastemask Top")
		(15 "B.Paste" user "Package Geometry/Pastemask Bottom")
		(5 "F.SilkS" user "Ref Des/Silkscreen Top")
		(7 "B.SilkS" user "Ref Des/Silkscreen Bottom")
		(1 "F.Mask" user "Board Geometry/Soldermask Top")
		(3 "B.Mask" user "Board Geometry/Soldermask Bottom")
		(17 "Dwgs.User" user "User.Drawings")
		(19 "Cmts.User" user "User.Comments")
		(21 "Eco1.User" user "User.Eco1")
		(23 "Eco2.User" user "User.Eco2")
		(25 "Edge.Cuts" user "Board Geometry/Outline")
		(27 "Margin" user)
		(31 "F.CrtYd" user "Package Geometry/Place Bound Top")
		(29 "B.CrtYd" user "Package Geometry/Place Bound Bottom")
		(35 "F.Fab" user "Ref Des/Assembly Top")
		(33 "B.Fab" user "Ref Des/Assembly Bottom")
	)
	(footprint ""
		(layer "F.Cu")
		(at 451.749922 -57.909968 -90)
		(property "Reference" "HDDSAS34"
			(at 0 0 270)
			(layer "F.SilkS")
			(hide yes)
			(effects
				(font
					(size 1.27 1.27)
				)
			)
		)
		(property "Value" "SKT-SAS15P-14P-45-GP"
			(at -20.7645 -8.9789 270)
			(unlocked yes)
			(layer "F.Fab")
			(hide yes)
			(effects
				(font
					(size 1.016 1.016)
					(thickness 0.1524)
				)
			)
		)
		(property "Device Type" "10120818-001C-TRLF"
			(at -20.7645 -10.5029 270)
			(unlocked yes)
			(layer "F.Fab")
			(hide yes)
			(effects
				(font
					(size 1.016 1.016)
					(thickness 0.1524)
				)
			)
		)
		(duplicate_pad_numbers_are_jumpers no)
		(fp_line
			(start 1.651 4.2926)
			(end 1.651 3.0099)
			(stroke
				(width 0.1524)
				(type default)
			)
			(layer "F.SilkS")
		)
		(fp_line
			(start 8.509 4.2926)
			(end 1.651 4.2926)
			(stroke
				(width 0.1524)
				(type default)
			)
			(layer "F.SilkS")
		)
		(fp_line
			(start -23.4188 3.0099)
			(end -23.4188 -3.2512)
			(stroke
				(width 0.1524)
				(type default)
			)
			(layer "F.SilkS")
		)
		(fp_line
			(start 1.651 3.0099)
			(end -23.4188 3.0099)
			(stroke
				(width 0.1524)
				(type default)
			)
			(layer "F.SilkS")
		)
		(fp_line
			(start 8.509 3.0099)
			(end 8.509 4.2926)
			(stroke
				(width 0.1524)
				(type default)
			)
			(layer "F.SilkS")
		)
		(fp_line
			(start 23.4188 3.0099)
			(end 8.509 3.0099)
			(stroke
				(width 0.1524)
				(type default)
			)
			(layer "F.SilkS")
		)
		(fp_line
			(start -23.4188 -3.2512)
			(end 23.4188 -3.2512)
			(stroke
				(width 0.1524)
				(type default)
			)
			(layer "F.SilkS")
		)
		(fp_line
			(start 23.4188 -3.2512)
			(end 23.4188 3.0099)
			(stroke
				(width 0.1524)
				(type default)
			)
			(layer "F.SilkS")
		)
		(fp_line
			(start 15.5067 -3.3401)
			(end 16.2687 -3.3401)
			(stroke
				(width 0.3302)
				(type default)
			)
			(layer "F.SilkS")
		)
		(fp_poly
			(pts
				(xy 15.868904 -3.230372) (xy 16.503904 -3.865372) (xy 15.233904 -3.865372)
			)
			(stroke
				(width 0)
				(type default)
			)
			(fill yes)
			(layer "F.SilkS")
		)
		(fp_poly
			(pts
				(xy -22.8727 -2.7559) (xy 22.8727 -2.7559) (xy 22.8727 2.7559) (xy 8.255 2.7559) (xy 8.255 3.5179)
				(xy 1.905 3.5179) (xy 1.905 2.7559) (xy -22.8727 2.7559)
			)
			(stroke
				(width 0)
				(type default)
			)
			(fill no)
			(layer "F.CrtYd")
		)
		(fp_poly
			(pts
				(xy 1.397 4.5466) (xy 1.397 3.2639) (xy -23.6728 3.2639) (xy -23.6728 -3.5052) (xy 23.6728 -3.5052)
				(xy 23.6728 -0.00635) (xy 22.8727 -0.00635) (xy 22.8727 -2.7559) (xy -22.8727 -2.7559) (xy -22.8727 2.7559)
				(xy 1.905 2.7559) (xy 1.905 3.5179) (xy 8.255 3.5179) (xy 8.255 2.7559) (xy 22.8727 2.7559) (xy 22.8727 0.00635)
				(xy 23.6728 0.00635) (xy 23.6728 3.2639) (xy 8.763 3.2639) (xy 8.763 4.5466)
			)
			(stroke
				(width 0)
				(type default)
			)
			(fill no)
			(layer "F.CrtYd")
		)
		(fp_poly
			(pts
				(xy 1.397 4.5466) (xy 1.397 3.2639) (xy -23.6728 3.2639) (xy -23.6728 -3.5052) (xy 23.6728 -3.5052)
				(xy 23.6728 3.2639) (xy 8.763 3.2639) (xy 8.763 4.5466)
			)
			(stroke
				(width 0)
				(type default)
			)
			(fill no)
			(layer "F.Fab")
		)
		(pad "" np_thru_hole circle
			(at -18.874994 0 270)
			(size 0.254 0.254)
			(drill 1.3462)
			(layers "*.Cu" "*.Mask")
			(clearance 0.9017)
			(thermal_gap 0.9017)
		)
		(pad "" np_thru_hole circle
			(at 18.874994 0 270)
			(size 0.254 0.254)
			(drill 0.9398)
			(layers "*.Cu" "*.Mask")
			(clearance 0.6985)
			(thermal_gap 0.6985)
		)
		(pad "G1" smd rect
			(at 21.874988 0 270)
			(size 2.5908 2.5908)
			(layers "F.Cu" "F.Mask" "F.Paste")
			(net "GND")
		)
		(pad "G2" smd rect
			(at -21.874988 0 270)
			(size 2.5908 2.5908)
			(layers "F.Cu" "F.Mask" "F.Paste")
			(net "GND")
		)
		(pad "P1" smd rect
			(at 1.905 -1.82499 270)
			(size 0.6096 2.3622)
			(layers "F.Cu" "F.Mask" "F.Paste")
			(net "Net_2036")
		)
		(pad "P2" smd rect
			(at 0.635 -1.82499 270)
			(size 0.6096 2.3622)
			(layers "F.Cu" "F.Mask" "F.Paste")
			(net "Net_2037")
		)
		(pad "P3" smd rect
			(at -0.635 -1.82499 270)
			(size 0.6096 2.3622)
			(layers "F.Cu" "F.Mask" "F.Paste")
			(net "Net_2038")
		)
		(pad "P4" smd rect
			(at -1.905 -1.82499 270)
			(size 0.6096 2.3622)
			(layers "F.Cu" "F.Mask" "F.Paste")
			(net "GND")
		)
		(pad "P5" smd rect
			(at -3.175 -1.82499 270)
			(size 0.6096 2.3622)
			(layers "F.Cu" "F.Mask" "F.Paste")
			(net "HDD_PRSNT_34")
		)
		(pad "P6" smd rect
			(at -4.445 -1.82499 270)
			(size 0.6096 2.3622)
			(layers "F.Cu" "F.Mask" "F.Paste")
			(net "GND")
		)
		(pad "P7" smd rect
			(at -5.715 -1.82499 270)
			(size 0.6096 2.3622)
			(layers "F.Cu" "F.Mask" "F.Paste")
			(net "5V_PRE_34")
		)
		(pad "P8" smd rect
			(at -6.985 -1.82499 270)
			(size 0.6096 2.3622)
			(layers "F.Cu" "F.Mask" "F.Paste")
			(net "P5V_HDD34")
		)
		(pad "P9" smd rect
			(at -8.255 -1.82499 270)
			(size 0.6096 2.3622)
			(layers "F.Cu" "F.Mask" "F.Paste")
			(net "P5V_HDD34")
		)
		(pad "P10" smd rect
			(at -9.525 -1.82499 270)
			(size 0.6096 2.3622)
			(layers "F.Cu" "F.Mask" "F.Paste")
			(net "GND")
		)
		(pad "P11" smd rect
			(at -10.795 -1.82499 270)
			(size 0.6096 2.3622)
			(layers "F.Cu" "F.Mask" "F.Paste")
			(net "ACT_HDD_34")
		)
		(pad "P12" smd rect
			(at -12.065 -1.82499 270)
			(size 0.6096 2.3622)
			(layers "F.Cu" "F.Mask" "F.Paste")
			(net "GND")
		)
		(pad "P13" smd rect
			(at -13.335 -1.82499 270)
			(size 0.6096 2.3622)
			(layers "F.Cu" "F.Mask" "F.Paste")
			(net "12V_PRE_34")
		)
		(pad "P14" smd rect
			(at -14.605 -1.82499 270)
			(size 0.6096 2.3622)
			(layers "F.Cu" "F.Mask" "F.Paste")
			(net "P12V_HDD34")
		)
		(pad "P15" smd rect
			(at -15.875 -1.82499 270)
			(size 0.6096 2.3622)
			(layers "F.Cu" "F.Mask" "F.Paste")
			(net "P12V_HDD34")
		)
		(pad "S1" smd rect
			(at 15.875 -1.82499 270)
			(size 0.6096 2.3622)
			(layers "F.Cu" "F.Mask" "F.Paste")
			(net "GND")
		)
		(pad "S2" smd rect
			(at 14.605 -1.82499 270)
			(size 0.6096 2.3622)
			(layers "F.Cu" "F.Mask" "F.Paste")
			(net "SAS_HDD_RX_P34")
		)
		(pad "S3" smd rect
			(at 13.335 -1.82499 270)
			(size 0.6096 2.3622)
			(layers "F.Cu" "F.Mask" "F.Paste")
			(net "SAS_HDD_RX_N34")
		)
		(pad "S4" smd rect
			(at 12.065 -1.82499 270)
			(size 0.6096 2.3622)
			(layers "F.Cu" "F.Mask" "F.Paste")
			(net "GND")
		)
		(pad "S5" smd rect
			(at 10.795 -1.82499 270)
			(size 0.6096 2.3622)
			(layers "F.Cu" "F.Mask" "F.Paste")
			(net "PHY_DRV_A_TO_SCC_A_34_DN")
		)
		(pad "S6" smd rect
			(at 9.525 -1.82499 270)
			(size 0.6096 2.3622)
			(layers "F.Cu" "F.Mask" "F.Paste")
			(net "PHY_DRV_A_TO_SCC_A_34_DP")
		)
		(pad "S7" smd rect
			(at 8.255 -1.82499 270)
			(size 0.6096 2.3622)
			(layers "F.Cu" "F.Mask" "F.Paste")
			(net "GND")
		)
		(pad "S8" smd rect
			(at 7.480046 2.845054 270)
			(size 0.508 2.3622)
			(layers "F.Cu" "F.Mask" "F.Paste")
			(net "GND")
		)
		(pad "S9" smd rect
			(at 6.679946 2.845054 270)
			(size 0.508 2.3622)
			(layers "F.Cu" "F.Mask" "F.Paste")
			(net "Net_473")
		)
		(pad "S10" smd rect
			(at 5.8801 2.845054 270)
			(size 0.508 2.3622)
			(layers "F.Cu" "F.Mask" "F.Paste")
			(net "Net_365")
		)
		(pad "S11" smd rect
			(at 5.08 2.845054 270)
			(size 0.508 2.3622)
			(layers "F.Cu" "F.Mask" "F.Paste")
			(net "GND")
		)
		(pad "S12" smd rect
			(at 4.2799 2.845054 270)
			(size 0.508 2.3622)
			(layers "F.Cu" "F.Mask" "F.Paste")
			(net "Net_401")
		)
		(pad "S13" smd rect
			(at 3.480054 2.845054 270)
			(size 0.508 2.3622)
			(layers "F.Cu" "F.Mask" "F.Paste")
			(net "Net_437")
		)
		(pad "S14" smd rect
			(at 2.679954 2.845054 270)
			(size 0.508 2.3622)
			(layers "F.Cu" "F.Mask" "F.Paste")
			(net "GND")
		)
		(zone
			(layer "F.Cu")
			(hatch none 0.5)
			(connect_pads
				(clearance 0)
			)
			(min_thickness 0.25)
			(keepout
				(tracks not_allowed)
				(vias allowed)
				(pads allowed)
				(copperpour not_allowed)
				(footprints allowed)
			)
			(placement
				(enabled no)
				(sheetname "")
			)
			(fill
				(thermal_gap 0.5)
				(thermal_bridge_width 0.5)
				(island_removal_mode 0)
			)
			(polygon
				(pts
					(xy 455.407522 -74.648568) (xy 448.333622 -74.648568) (xy 448.333622 -81.582768) (xy 449.438522 -81.582768)
					(xy 449.438522 -77.467968) (xy 454.061322 -77.467968) (xy 454.061322 -81.582768) (xy 455.407522 -81.582768)
				)
			)
		)
		(zone
			(layer "F.Cu")
			(hatch none 0.5)
			(connect_pads
				(clearance 0)
			)
			(min_thickness 0.25)
			(keepout
				(tracks allowed)
				(vias not_allowed)
				(pads allowed)
				(copperpour not_allowed)
				(footprints allowed)
			)
			(placement
				(enabled no)
				(sheetname "")
			)
			(fill
				(thermal_gap 0.5)
				(thermal_bridge_width 0.5)
				(island_removal_mode 0)
			)
			(polygon
				(pts
					(xy 455.407522 -74.648568) (xy 448.333622 -74.648568) (xy 448.333622 -81.582768) (xy 449.438522 -81.582768)
					(xy 449.438522 -77.467968) (xy 454.061322 -77.467968) (xy 454.061322 -81.582768) (xy 455.407522 -81.582768)
				)
			)
		)
		(zone
			(layer "F.Cu")
			(hatch none 0.5)
			(connect_pads
				(clearance 0)
			)
			(min_thickness 0.25)
			(keepout
				(tracks not_allowed)
				(vias allowed)
				(pads allowed)
				(copperpour not_allowed)
				(footprints allowed)
			)
			(placement
				(enabled no)
				(sheetname "")
			)
			(fill
				(thermal_gap 0.5)
				(thermal_bridge_width 0.5)
				(island_removal_mode 0)
			)
			(polygon
				(pts
					(xy 455.407522 -41.171368) (xy 448.333622 -41.171368) (xy 448.333622 -34.237168) (xy 449.438522 -34.237168)
					(xy 449.438522 -38.351968) (xy 454.061322 -38.351968) (xy 454.061322 -34.237168) (xy 455.407522 -34.237168)
				)
			)
		)
		(zone
			(layer "F.Cu")
			(hatch none 0.5)
			(connect_pads
				(clearance 0)
			)
			(min_thickness 0.25)
			(keepout
				(tracks allowed)
				(vias not_allowed)
				(pads allowed)
				(copperpour not_allowed)
				(footprints allowed)
			)
			(placement
				(enabled no)
				(sheetname "")
			)
			(fill
				(thermal_gap 0.5)
				(thermal_bridge_width 0.5)
				(island_removal_mode 0)
			)
			(polygon
				(pts
					(xy 455.407522 -41.171368) (xy 448.333622 -41.171368) (xy 448.333622 -34.237168) (xy 449.438522 -34.237168)
					(xy 449.438522 -38.351968) (xy 454.061322 -38.351968) (xy 454.061322 -34.237168) (xy 455.407522 -34.237168)
				)
			)
		)
		(zone
			(layers "F.Cu" "B.Cu" "In1.Cu" "In2.Cu" "In3.Cu" "In4.Cu" "In5.Cu" "In6.Cu"
				"In7.Cu" "In8.Cu" "In9.Cu" "In10.Cu"
			)
			(hatch none 0.5)
			(connect_pads
				(clearance 0)
			)
			(min_thickness 0.25)
			(keepout
				(tracks not_allowed)
				(vias allowed)
				(pads allowed)
				(copperpour not_allowed)
				(footprints allowed)
			)
			(placement
				(enabled no)
				(sheetname "")
			)
			(fill
				(thermal_gap 0.5)
				(thermal_bridge_width 0.5)
				(island_removal_mode 0)
			)
			(polygon
				(pts
					(arc
						(start 452.524622 -39.034974)
						(mid 450.975222 -39.034974)
						(end 452.524622 -39.034974)
					)
				)
			)
		)
		(zone
			(layers "F.Cu" "B.Cu" "In1.Cu" "In2.Cu" "In3.Cu" "In4.Cu" "In5.Cu" "In6.Cu"
				"In7.Cu" "In8.Cu" "In9.Cu" "In10.Cu"
			)
			(hatch none 0.5)
			(connect_pads
				(clearance 0)
			)
			(min_thickness 0.25)
			(keepout
				(tracks not_allowed)
				(vias allowed)
				(pads allowed)
				(copperpour not_allowed)
				(footprints allowed)
			)
			(placement
				(enabled no)
				(sheetname "")
			)
			(fill
				(thermal_gap 0.5)
				(thermal_bridge_width 0.5)
				(island_removal_mode 0)
			)
			(polygon
				(pts
					(arc
						(start 452.727822 -76.784962)
						(mid 450.772022 -76.784962)
						(end 452.727822 -76.784962)
					)
				)
			)
		)
	)
	(footprint ""
		(layer "F.Cu")
		(at 172.466 -294.683942 -90)
		(property "Reference" "C110"
			(at 0 0 270)
			(layer "F.SilkS")
			(hide yes)
			(effects
				(font
					(size 1.27 1.27)
				)
			)
		)
		(property "Value" "SC4D7U25V5KX-1-GP"
			(at -0.0762 -6.1214 270)
			(unlocked yes)
			(layer "F.Fab")
			(hide yes)
			(effects
				(font
					(size 1.016 1.016)
					(thickness 0.1524)
				)
			)
		)
		(property "Device Type" "C805H58"
			(at -0.0762 -8.1534 270)
			(unlocked yes)
			(layer "F.Fab")
			(hide yes)
			(effects
				(font
					(size 1.016 1.016)
					(thickness 0.1524)
				)
			)
		)
		(duplicate_pad_numbers_are_jumpers no)
		(fp_line
			(start 0.635 0)
			(end -0.635 0)
			(stroke
				(width 0.508)
				(type default)
			)
			(layer "F.SilkS")
		)
		(fp_rect
			(start -0.9652 1.778)
			(end 0.9652 -1.778)
			(stroke
				(width 0)
				(type default)
			)
			(fill no)
			(layer "F.CrtYd")
		)
		(fp_poly
			(pts
				(xy -0.9652 -1.778) (xy 0.9652 -1.778) (xy 0.9652 1.778) (xy -0.9652 1.778)
			)
			(stroke
				(width 0)
				(type default)
			)
			(fill no)
			(layer "F.Fab")
		)
		(pad "1" smd rect
			(at 0 -0.9652 270)
			(size 1.397 1.143)
			(layers "F.Cu" "F.Mask" "F.Paste")
			(net "P12V_HDD5")
		)
		(pad "2" smd rect
			(at 0 0.9652 270)
			(size 1.397 1.143)
			(layers "F.Cu" "F.Mask" "F.Paste")
			(net "GND")
		)
	)
	(footprint ""
		(layer "F.Cu")
		(at 224.572322 -131.11607 -90)
		(property "Reference" "TP205"
			(at 0 0 270)
			(layer "F.SilkS")
			(hide yes)
			(effects
				(font
					(size 1.27 1.27)
				)
			)
		)
		(property "Value" "TPAD32-GP"
			(at -0.0508 -1.6764 270)
			(unlocked yes)
			(layer "F.Fab")
			(hide yes)
			(effects
				(font
					(size 1.016 1.016)
					(thickness 0.1524)
				)
			)
		)
		(property "Device Type" "TPAD32"
			(at -0.0508 -3.2004 270)
			(unlocked yes)
			(layer "F.Fab")
			(hide yes)
			(effects
				(font
					(size 1.016 1.016)
					(thickness 0.1524)
				)
			)
		)
		(duplicate_pad_numbers_are_jumpers no)
		(fp_poly
			(pts
				(arc
					(start 0 -0.4064)
					(mid 0 0.4064)
					(end 0 -0.4064)
				)
			)
			(stroke
				(width 0)
				(type default)
			)
			(fill no)
			(layer "F.CrtYd")
		)
		(fp_poly
			(pts
				(arc
					(start 0 -0.7112)
					(mid 0 0.7112)
					(end 0 -0.7112)
				)
			)
			(stroke
				(width 0)
				(type default)
			)
			(fill no)
			(layer "F.Fab")
		)
		(pad "1" smd circle
			(at 0 0 270)
			(size 0.8128 0.8128)
			(layers "F.Cu" "F.Mask" "F.Paste")
			(net "TP_COMP_A_SATA_P0_RX_DP")
		)
	)
	(footprint ""
		(layer "F.Cu")
		(at 445.0207 -61.102494 -90)
		(property "Reference" "C487"
			(at 0 0 270)
			(layer "F.SilkS")
			(hide yes)
			(effects
				(font
					(size 1.27 1.27)
				)
			)
		)
		(property "Value" "SCD01U50V2KX-1GP"
			(at 1.1811 -2.7051 270)
			(unlocked yes)
			(layer "F.Fab")
			(hide yes)
			(effects
				(font
					(size 1.016 1.016)
					(thickness 0.1524)
				)
			)
		)
		(property "Device Type" "C402H22"
			(at 1.1811 -4.2291 270)
			(unlocked yes)
			(layer "F.Fab")
			(hide yes)
			(effects
				(font
					(size 1.016 1.016)
					(thickness 0.1524)
				)
			)
		)
		(duplicate_pad_numbers_are_jumpers no)
		(fp_rect
			(start -0.4318 0.9525)
			(end 0.4318 -0.9525)
			(stroke
				(width 0)
				(type default)
			)
			(fill no)
			(layer "F.CrtYd")
		)
		(fp_rect
			(start -0.4318 0.9525)
			(end 0.4318 -0.9525)
			(stroke
				(width 0)
				(type default)
			)
			(fill no)
			(layer "F.Fab")
		)
		(pad "1" smd custom
			(at 0 -0.4445 270)
			(size 0.1524 0.1524)
			(layers "F.Cu" "F.Mask" "F.Paste")
			(net "HDD_PRSNT_34")
			(options
				(clearance outline)
				(anchor circle)
			)
			(primitives
				(gr_poly
					(pts
						(arc
							(start 0.3048 -0.2032)
							(mid 0.275042 -0.275042)
							(end 0.2032 -0.3048)
						)
						(arc
							(start -0.2032 -0.3048)
							(mid -0.275042 -0.275042)
							(end -0.3048 -0.2032)
						)
						(arc
							(start -0.3048 0.2032)
							(mid -0.275042 0.275042)
							(end -0.2032 0.3048)
						)
						(arc
							(start 0.2032 0.3048)
							(mid 0.275042 0.275042)
							(end 0.3048 0.2032)
						)
					)
					(width 0)
					(fill yes)
				)
			)
		)
		(pad "2" smd custom
			(at 0 0.4445 270)
			(size 0.1524 0.1524)
			(layers "F.Cu" "F.Mask" "F.Paste")
			(net "GND")
			(options
				(clearance outline)
				(anchor circle)
			)
			(primitives
				(gr_poly
					(pts
						(arc
							(start 0.3048 -0.2032)
							(mid 0.275042 -0.275042)
							(end 0.2032 -0.3048)
						)
						(arc
							(start -0.2032 -0.3048)
							(mid -0.275042 -0.275042)
							(end -0.3048 -0.2032)
						)
						(arc
							(start -0.3048 0.2032)
							(mid -0.275042 0.275042)
							(end -0.2032 0.3048)
						)
						(arc
							(start 0.2032 0.3048)
							(mid 0.275042 0.275042)
							(end 0.3048 0.2032)
						)
					)
					(width 0)
					(fill yes)
				)
			)
		)
	)
)
